(kicad_pcb
	(version 20241229)
	(generator "pcbnew")
	(generator_version "9.0")
	(general
		(thickness 1.63)
		(legacy_teardrops no)
	)
	(paper "A4")
	(title_block
		(title "CM4 Baseboard")
		(date "2026-01-05")
		(rev "1.1.1")
		(company "Antmicro Ltd")
		(comment 1 "www.antmicro.com")
		(comment 9 "footprints 60-61 of 506")
	)
	(layers
		(0 "F.Cu" signal)
		(4 "In1.Cu" power)
		(6 "In2.Cu" power)
		(8 "In3.Cu" signal)
		(10 "In4.Cu" signal)
		(2 "B.Cu" signal)
		(9 "F.Adhes" user "F.Adhesive")
		(11 "B.Adhes" user "B.Adhesive")
		(13 "F.Paste" user)
		(15 "B.Paste" user)
		(5 "F.SilkS" user "F.Silkscreen")
		(7 "B.SilkS" user "B.Silkscreen")
		(1 "F.Mask" user)
		(3 "B.Mask" user)
		(17 "Dwgs.User" user "User.Drawings")
		(19 "Cmts.User" user "User.Comments")
		(21 "Eco1.User" user "User.Eco1")
		(23 "Eco2.User" user "User.Eco2")
		(25 "Edge.Cuts" user)
		(27 "Margin" user)
		(31 "F.CrtYd" user "F.Courtyard")
		(29 "B.CrtYd" user "B.Courtyard")
		(35 "F.Fab" user)
		(33 "B.Fab" user)
	)
	(footprint "antmicro-footprints:VFQFN-40-1EP_6x6mm"
		(layer "F.Cu")
		(at 71.567962 171.8165 -90)
		(property "Reference" "U801"
			(at -3.7665 -3.422038 0)
			(layer "F.SilkS")
			(effects
				(font
					(size 0.7 0.7)
					(thickness 0.15)
				)
				(justify left top)
			)
		)
		(property "Value" "PN7160A1_VFQFN"
			(at 0 4.6 90)
			(layer "F.Fab")
			(effects
				(font
					(size 0.7 0.7)
					(thickness 0.15)
				)
				(justify right bottom)
			)
		)
		(property "Datasheet" "https://www.nxp.com/docs/en/data-sheet/PN7160_PN7161.pdf"
			(at 0 0 90)
			(layer "F.Fab")
			(hide yes)
			(effects
				(font
					(size 1.27 1.27)
					(thickness 0.15)
				)
			)
		)
		(property "MPN" "PN7160A1HN/C100E"
			(at 0 0 270)
			(unlocked yes)
			(layer "F.Fab")
			(hide yes)
			(effects
				(font
					(size 1 1)
					(thickness 0.15)
				)
			)
		)
		(property "Manufacturer" "NXP"
			(at 0 0 270)
			(unlocked yes)
			(layer "F.Fab")
			(hide yes)
			(effects
				(font
					(size 1 1)
					(thickness 0.15)
				)
			)
		)
		(property "Author" "Antmicro"
			(at 0 0 270)
			(unlocked yes)
			(layer "F.Fab")
			(hide yes)
			(effects
				(font
					(size 1 1)
					(thickness 0.15)
				)
			)
		)
		(property "License" "Apache-2.0"
			(at 0 0 270)
			(unlocked yes)
			(layer "F.Fab")
			(hide yes)
			(effects
				(font
					(size 1 1)
					(thickness 0.15)
				)
			)
		)
		(property ki_fp_filters "QFN40_PN7160_NXP QFN40_PN7160_NXP-M QFN40_PN7160_NXP-L")
		(sheetname "/Peripherals/")
		(sheetfile "peripherals.kicad_sch")
		(attr smd)
		(fp_line
			(start -3.125 3.125)
			(end -3.125 2.675)
			(stroke
				(width 0.15)
				(type solid)
			)
			(layer "F.SilkS")
		)
		(fp_line
			(start -2.725 3.125)
			(end -3.125 3.125)
			(stroke
				(width 0.15)
				(type solid)
			)
			(layer "F.SilkS")
		)
		(fp_line
			(start 3.125 3.125)
			(end 2.575 3.125)
			(stroke
				(width 0.15)
				(type solid)
			)
			(layer "F.SilkS")
		)
		(fp_line
			(start 3.125 2.575)
			(end 3.125 3.125)
			(stroke
				(width 0.15)
				(type solid)
			)
			(layer "F.SilkS")
		)
		(fp_line
			(start -3.125 -2.625)
			(end -3.125 -2.5)
			(stroke
				(width 0.15)
				(type solid)
			)
			(layer "F.SilkS")
		)
		(fp_line
			(start 3.125 -2.625)
			(end 3.125 -3.125)
			(stroke
				(width 0.15)
				(type solid)
			)
			(layer "F.SilkS")
		)
		(fp_line
			(start -2.725 -3.125)
			(end -3.125 -2.625)
			(stroke
				(width 0.15)
				(type solid)
			)
			(layer "F.SilkS")
		)
		(fp_line
			(start -2.525 -3.125)
			(end -2.725 -3.125)
			(stroke
				(width 0.15)
				(type solid)
			)
			(layer "F.SilkS")
		)
		(fp_line
			(start 3.125 -3.125)
			(end 2.575 -3.125)
			(stroke
				(width 0.15)
				(type solid)
			)
			(layer "F.SilkS")
		)
		(fp_circle
			(center -3.4 -2.6)
			(end -3.35 -2.6)
			(stroke
				(width 0.15)
				(type solid)
			)
			(fill yes)
			(layer "F.SilkS")
		)
		(fp_line
			(start -3.68 3.68)
			(end 3.68 3.68)
			(stroke
				(width 0.05)
				(type solid)
			)
			(layer "F.CrtYd")
		)
		(fp_line
			(start -3.68 -3.68)
			(end -3.68 3.68)
			(stroke
				(width 0.05)
				(type solid)
			)
			(layer "F.CrtYd")
		)
		(fp_line
			(start 3.68 -3.68)
			(end 3.68 3.68)
			(stroke
				(width 0.05)
				(type solid)
			)
			(layer "F.CrtYd")
		)
		(fp_line
			(start 3.68 -3.68)
			(end -3.68 -3.68)
			(stroke
				(width 0.05)
				(type solid)
			)
			(layer "F.CrtYd")
		)
		(fp_line
			(start -3.025 3.025)
			(end 3.025 3.025)
			(stroke
				(width 0.15)
				(type solid)
			)
			(layer "F.Fab")
		)
		(fp_line
			(start -3.025 -2.525)
			(end -3.025 3.025)
			(stroke
				(width 0.15)
				(type solid)
			)
			(layer "F.Fab")
		)
		(fp_line
			(start -2.625 -3.025)
			(end -3.025 -2.525)
			(stroke
				(width 0.15)
				(type solid)
			)
			(layer "F.Fab")
		)
		(fp_line
			(start -2.625 -3.025)
			(end 3.025 -3.025)
			(stroke
				(width 0.15)
				(type solid)
			)
			(layer "F.Fab")
		)
		(fp_line
			(start 3.025 -3.025)
			(end 3.025 3.025)
			(stroke
				(width 0.15)
				(type solid)
			)
			(layer "F.Fab")
		)
		(fp_text user "${REFERENCE}"
			(at -4.03 6.6 90)
			(layer "F.Fab")
			(effects
				(font
					(size 0.7 0.7)
					(thickness 0.15)
					(italic yes)
				)
				(justify right top)
			)
		)
		(fp_text user "Author: Antmicro"
			(at 0 5.75 90)
			(layer "F.Fab")
			(effects
				(font
					(size 0.7 0.7)
					(thickness 0.15)
				)
				(justify right bottom)
			)
		)
		(fp_text user "License: Apache-2.0"
			(at 0 6.95 90)
			(layer "F.Fab")
			(effects
				(font
					(size 0.7 0.7)
					(thickness 0.15)
				)
				(justify right bottom)
			)
		)
		(pad "1" smd rect
			(at -2.975 -2.25 270)
			(size 0.85 0.28)
			(layers "F.Cu" "F.Mask" "F.Paste")
			(net 374 "Net-(U801-I2C_ADR0)")
			(pinfunction "I2C_ADR0")
			(pintype "bidirectional")
			(solder_mask_margin 0.07)
		)
		(pad "2" smd rect
			(at -2.975 -1.75 270)
			(size 0.85 0.28)
			(layers "F.Cu" "F.Mask" "F.Paste")
			(net 287 "/Compute module/NFC.DWL_REQ")
			(pinfunction "DWL_REQ")
			(pintype "input")
			(solder_mask_margin 0.07)
		)
		(pad "3" smd rect
			(at -2.975 -1.25 270)
			(size 0.85 0.28)
			(layers "F.Cu" "F.Mask" "F.Paste")
			(net 375 "Net-(U801-I2C_ADR1)")
			(pinfunction "I2C_ADR1")
			(pintype "bidirectional")
			(solder_mask_margin 0.07)
		)
		(pad "4" smd rect
			(at -2.975 -0.75 270)
			(size 0.85 0.28)
			(layers "F.Cu" "F.Mask" "F.Paste")
			(net 3 "GND")
			(pinfunction "VSS")
			(pintype "power_out")
			(solder_mask_margin 0.07)
		)
		(pad "5" smd rect
			(at -2.975 -0.25 270)
			(size 0.85 0.28)
			(layers "F.Cu" "F.Mask" "F.Paste")
			(net 143 "/CSI/I_{2}C1.SDA")
			(pinfunction "I2C_SDA")
			(pintype "bidirectional")
			(solder_mask_margin 0.07)
		)
		(pad "6" smd rect
			(at -2.975 0.25 270)
			(size 0.85 0.28)
			(layers "F.Cu" "F.Mask" "F.Paste")
			(net 9 "+3V3")
			(pinfunction "V_{DD(PAD)}")
			(pintype "power_in")
			(solder_mask_margin 0.07)
		)
		(pad "7" smd rect
			(at -2.975 0.75 270)
			(size 0.85 0.28)
			(layers "F.Cu" "F.Mask" "F.Paste")
			(net 142 "/CSI/I_{2}C1.SCL")
			(pinfunction "I2C_SCL")
			(pintype "bidirectional")
			(solder_mask_margin 0.07)
		)
		(pad "8" smd rect
			(at -2.975 1.25 270)
			(size 0.85 0.28)
			(layers "F.Cu" "F.Mask" "F.Paste")
			(net 286 "/Compute module/NFC.IRQ")
			(pinfunction "IRQ")
			(pintype "output")
			(solder_mask_margin 0.07)
		)
		(pad "9" smd rect
			(at -2.975 1.75 270)
			(size 0.85 0.28)
			(layers "F.Cu" "F.Mask" "F.Paste")
			(net 3 "GND")
			(pinfunction "VSS")
			(pintype "power_out")
			(solder_mask_margin 0.07)
		)
		(pad "10" smd rect
			(at -2.975 2.25 270)
			(size 0.85 0.28)
			(layers "F.Cu" "F.Mask" "F.Paste")
			(net 285 "/Compute module/NFC.EN")
			(pinfunction "VEN/~{RST}")
			(pintype "input")
			(solder_mask_margin 0.07)
		)
		(pad "11" smd rect
			(at -2.25 2.975 270)
			(size 0.28 0.85)
			(layers "F.Cu" "F.Mask" "F.Paste")
			(net 398 "unconnected-(U801-IC-Pad11)")
			(pinfunction "IC")
			(pintype "no_connect")
			(solder_mask_margin 0.07)
		)
		(pad "12" smd rect
			(at -1.75 2.975 270)
			(size 0.28 0.85)
			(layers "F.Cu" "F.Mask" "F.Paste")
			(net 501 "Net-(U801-V_{DD(UP)})")
			(pinfunction "V_{BAT}")
			(pintype "passive")
			(solder_mask_margin 0.07)
		)
		(pad "13" smd rect
			(at -1.25 2.975 270)
			(size 0.28 0.85)
			(layers "F.Cu" "F.Mask" "F.Paste")
			(net 501 "Net-(U801-V_{DD(UP)})")
			(pinfunction "V_{DD(UP)}")
			(pintype "power_in")
			(solder_mask_margin 0.07)
		)
		(pad "14" smd rect
			(at -0.75 2.975 270)
			(size 0.28 0.85)
			(layers "F.Cu" "F.Mask" "F.Paste")
			(net 94 "Net-(U801-TVDD_IN)")
			(pinfunction "V_{DD(TX)}")
			(pintype "power_in")
			(solder_mask_margin 0.07)
		)
		(pad "15" smd rect
			(at -0.25 2.975 270)
			(size 0.28 0.85)
			(layers "F.Cu" "F.Mask" "F.Paste")
			(net 105 "Net-(U801-RXN)")
			(pinfunction "RXN")
			(pintype "input")
			(solder_mask_margin 0.07)
		)
		(pad "16" smd rect
			(at 0.25 2.975 270)
			(size 0.28 0.85)
			(layers "F.Cu" "F.Mask" "F.Paste")
			(net 103 "Net-(U801-RXP)")
			(pinfunction "RXP")
			(pintype "input")
			(solder_mask_margin 0.07)
		)
		(pad "17" smd rect
			(at 0.75 2.975 270)
			(size 0.28 0.85)
			(layers "F.Cu" "F.Mask" "F.Paste")
			(net 95 "Net-(U801-V_{DD(VMID)})")
			(pinfunction "V_{DD(VMID)}")
			(pintype "power_in")
			(solder_mask_margin 0.07)
		)
		(pad "18" smd rect
			(at 1.25 2.975 270)
			(size 0.28 0.85)
			(layers "F.Cu" "F.Mask" "F.Paste")
			(net 94 "Net-(U801-TVDD_IN)")
			(pinfunction "TVDD_IN")
			(pintype "power_in")
			(solder_mask_margin 0.07)
		)
		(pad "19" smd rect
			(at 1.75 2.975 270)
			(size 0.28 0.85)
			(layers "F.Cu" "F.Mask" "F.Paste")
			(net 326 "Net-(U801-TX2)")
			(pinfunction "TX2")
			(pintype "output")
			(solder_mask_margin 0.07)
		)
		(pad "20" smd rect
			(at 2.25 2.975 270)
			(size 0.28 0.85)
			(layers "F.Cu" "F.Mask" "F.Paste")
			(net 3 "GND")
			(pinfunction "VSS")
			(pintype "power_out")
			(solder_mask_margin 0.07)
		)
		(pad "21" smd rect
			(at 2.975 2.25 270)
			(size 0.85 0.28)
			(layers "F.Cu" "F.Mask" "F.Paste")
			(net 325 "Net-(U801-TX1)")
			(pinfunction "TX1")
			(pintype "output")
			(solder_mask_margin 0.07)
		)
		(pad "22" smd rect
			(at 2.975 1.75 270)
			(size 0.85 0.28)
			(layers "F.Cu" "F.Mask" "F.Paste")
			(net 94 "Net-(U801-TVDD_IN)")
			(pinfunction "TVDD_IN2")
			(pintype "power_in")
			(solder_mask_margin 0.07)
		)
		(pad "23" smd rect
			(at 2.975 1.25 270)
			(size 0.85 0.28)
			(layers "F.Cu" "F.Mask" "F.Paste")
			(net 101 "Net-(U801-ANT1)")
			(pinfunction "ANT1")
			(pintype "bidirectional")
			(solder_mask_margin 0.07)
		)
		(pad "24" smd rect
			(at 2.975 0.75 270)
			(size 0.85 0.28)
			(layers "F.Cu" "F.Mask" "F.Paste")
			(net 107 "Net-(U801-ANT2)")
			(pinfunction "ANT2")
			(pintype "bidirectional")
			(solder_mask_margin 0.07)
		)
		(pad "25" smd rect
			(at 2.975 0.25 270)
			(size 0.85 0.28)
			(layers "F.Cu" "F.Mask" "F.Paste")
			(net 383 "Net-(U801-V_{DD(HF)})")
			(pinfunction "V_{DD(HF)}")
			(pintype "power_in")
			(solder_mask_margin 0.07)
		)
		(pad "26" smd rect
			(at 2.975 -0.25 270)
			(size 0.85 0.28)
			(layers "F.Cu" "F.Mask" "F.Paste")
			(net 93 "Net-(U801-V_{DD(A)})")
			(pinfunction "V_{DD(A)}")
			(pintype "power_in")
			(solder_mask_margin 0.07)
		)
		(pad "27" smd rect
			(at 2.975 -0.75 270)
			(size 0.96 0.28)
			(layers "F.Cu" "F.Mask" "F.Paste")
			(net 93 "Net-(U801-V_{DD(A)})")
			(pinfunction "V_{DD}")
			(pintype "power_in")
			(solder_mask_margin 0.07)
		)
		(pad "28" smd rect
			(at 2.975 -1.25 270)
			(size 0.85 0.28)
			(layers "F.Cu" "F.Mask" "F.Paste")
			(net 501 "Net-(U801-V_{DD(UP)})")
			(pinfunction "V_{BAT}")
			(pintype "power_in")
			(solder_mask_margin 0.07)
		)
		(pad "29" smd rect
			(at 2.975 -1.75 270)
			(size 0.85 0.28)
			(layers "F.Cu" "F.Mask" "F.Paste")
			(net 99 "Net-(U801-XTAL2)")
			(pinfunction "XTAL2")
			(pintype "output")
			(solder_mask_margin 0.07)
		)
		(pad "30" smd rect
			(at 2.975 -2.25 270)
			(size 0.85 0.28)
			(layers "F.Cu" "F.Mask" "F.Paste")
			(net 108 "Net-(U801-CLK_XTAL1)")
			(pinfunction "CLK_XTAL1")
			(pintype "input")
			(solder_mask_margin 0.07)
		)
		(pad "31" smd rect
			(at 2.25 -2.975 270)
			(size 0.28 0.85)
			(layers "F.Cu" "F.Mask" "F.Paste")
			(net 93 "Net-(U801-V_{DD(A)})")
			(pinfunction "V_{DD(D)}")
			(pintype "power_in")
			(solder_mask_margin 0.07)
		)
		(pad "32" smd rect
			(at 1.75 -2.975 270)
			(size 0.28 0.85)
			(layers "F.Cu" "F.Mask" "F.Paste")
			(net 399 "unconnected-(U801-NC-Pad32)")
			(pinfunction "NC")
			(pintype "no_connect")
			(solder_mask_margin 0.07)
		)
		(pad "33" smd rect
			(at 1.25 -2.975 270)
			(size 0.28 0.85)
			(layers "F.Cu" "F.Mask" "F.Paste")
			(net 400 "unconnected-(U801-NC-Pad33)")
			(pinfunction "NC")
			(pintype "no_connect")
			(solder_mask_margin 0.07)
		)
		(pad "34" smd rect
			(at 0.75 -2.975 270)
			(size 0.28 0.85)
			(layers "F.Cu" "F.Mask" "F.Paste")
			(net 401 "unconnected-(U801-NC-Pad34)")
			(pinfunction "NC")
			(pintype "no_connect")
			(solder_mask_margin 0.07)
		)
		(pad "35" smd rect
			(at 0.25 -2.975 270)
			(size 0.28 0.85)
			(layers "F.Cu" "F.Mask" "F.Paste")
			(net 402 "unconnected-(U801-NC-Pad35)")
			(pinfunction "NC")
			(pintype "no_connect")
			(solder_mask_margin 0.07)
		)
		(pad "36" smd rect
			(at -0.25 -2.975 270)
			(size 0.28 0.85)
			(layers "F.Cu" "F.Mask" "F.Paste")
			(net 403 "unconnected-(U801-NC-Pad36)")
			(pinfunction "NC")
			(pintype "no_connect")
			(solder_mask_margin 0.07)
		)
		(pad "37" smd rect
			(at -0.75 -2.975 270)
			(size 0.28 0.85)
			(layers "F.Cu" "F.Mask" "F.Paste")
			(net 381 "Net-(U801-DCDC_EN)")
			(pinfunction "DCDC_EN")
			(pintype "output")
			(solder_mask_margin 0.07)
		)
		(pad "38" smd rect
			(at -1.25 -2.975 270)
			(size 0.28 0.85)
			(layers "F.Cu" "F.Mask" "F.Paste")
			(net 404 "unconnected-(U801-IC-Pad38)")
			(pinfunction "IC")
			(pintype "no_connect")
			(solder_mask_margin 0.07)
		)
		(pad "39" smd rect
			(at -1.75 -2.975 270)
			(size 0.28 0.85)
			(layers "F.Cu" "F.Mask" "F.Paste")
			(net 328 "/Compute module/NFC.WKUP_REQ")
			(pinfunction "WKUP_REQ")
			(pintype "input")
			(solder_mask_margin 0.07)
		)
		(pad "40" smd rect
			(at -2.25 -2.975 270)
			(size 0.28 0.85)
			(layers "F.Cu" "F.Mask" "F.Paste")
			(net 382 "Net-(U801-CLK_REQ)")
			(pinfunction "CLK_REQ")
			(pintype "output")
			(solder_mask_margin 0.07)
		)
		(pad "41" smd rect
			(at 0 0 270)
			(size 4.5 4.5)
			(layers "F.Cu" "F.Mask" "F.Paste")
			(net 3 "GND")
			(pinfunction "VSS")
			(pintype "passive")
		)
	)
	(footprint "antmicro-footprints:TSOT23-6"
		(layer "F.Cu")
		(at 132.917962 158.6165 -90)
		(property "Reference" "U602"
			(at 1.12 1.65 0)
			(layer "F.SilkS")
			(effects
				(font
					(size 0.7 0.7)
					(thickness 0.15)
				)
				(justify right bottom)
			)
		)
		(property "Value" "AP22615A_TSOT26"
			(at 0 2.6 90)
			(layer "F.Fab")
			(effects
				(font
					(size 0.7 0.7)
					(thickness 0.15)
				)
				(justify right bottom)
			)
		)
		(property "Datasheet" "https://www.mouser.com/datasheet/2/115/DIOD_S_A0008958405_1-2543193.pdf"
			(at 0 0 270)
			(layer "F.Fab")
			(hide yes)
			(effects
				(font
					(size 1.27 1.27)
					(thickness 0.15)
				)
			)
		)
		(property "MPN" "AP22615AWU-7"
			(at 0 0 270)
			(unlocked yes)
			(layer "F.Fab")
			(hide yes)
			(effects
				(font
					(size 1 1)
					(thickness 0.15)
				)
			)
		)
		(property "Manufacturer" "Diodes Incorporated"
			(at 0 0 270)
			(unlocked yes)
			(layer "F.Fab")
			(hide yes)
			(effects
				(font
					(size 1 1)
					(thickness 0.15)
				)
			)
		)
		(property "Author" "Antmicro"
			(at 0 0 270)
			(unlocked yes)
			(layer "F.Fab")
			(hide yes)
			(effects
				(font
					(size 1 1)
					(thickness 0.15)
				)
			)
		)
		(property "License" "Apache-2.0"
			(at 0 0 270)
			(unlocked yes)
			(layer "F.Fab")
			(hide yes)
			(effects
				(font
					(size 1 1)
					(thickness 0.15)
				)
			)
		)
		(sheetname "/CSI/")
		(sheetfile "csi.kicad_sch")
		(attr smd)
		(fp_line
			(start -1 1.55)
			(end -1 1.4)
			(stroke
				(width 0.15)
				(type solid)
			)
			(layer "F.SilkS")
		)
		(fp_line
			(start 1 1.55)
			(end -1 1.55)
			(stroke
				(width 0.15)
				(type solid)
			)
			(layer "F.SilkS")
		)
		(fp_line
			(start 1 1.55)
			(end 1 1.4)
			(stroke
				(width 0.15)
				(type solid)
			)
			(layer "F.SilkS")
		)
		(fp_line
			(start 1 -1.497)
			(end 1 -1.375)
			(stroke
				(width 0.15)
				(type solid)
			)
			(layer "F.SilkS")
		)
		(fp_line
			(start 1 -1.497)
			(end -1 -1.5)
			(stroke
				(width 0.15)
				(type solid)
			)
			(layer "F.SilkS")
		)
		(fp_line
			(start -1 -1.5)
			(end -1 -1.375)
			(stroke
				(width 0.15)
				(type solid)
			)
			(layer "F.SilkS")
		)
		(fp_circle
			(center -1.44 -1.5)
			(end -1.39 -1.5)
			(stroke
				(width 0.15)
				(type solid)
			)
			(fill yes)
			(layer "F.SilkS")
		)
		(fp_rect
			(start 1.93 -1.7)
			(end -1.93 1.7)
			(stroke
				(width 0.05)
				(type solid)
			)
			(fill no)
			(layer "F.CrtYd")
		)
		(fp_line
			(start -0.45 -1.521)
			(end -0.876 -1.096)
			(stroke
				(width 0.15)
				(type solid)
			)
			(layer "F.Fab")
		)
		(fp_rect
			(start 0.875 1.528)
			(end -0.875 -1.525)
			(stroke
				(width 0.15)
				(type solid)
			)
			(fill no)
			(layer "F.Fab")
		)
		(fp_text user "License: Apache-2.0"
			(at -1.93 6.199 270)
			(layer "F.Fab")
			(effects
				(font
					(size 0.7 0.7)
					(thickness 0.15)
				)
				(justify left bottom)
			)
		)
		(fp_text user "${REFERENCE}"
			(at -1.93 3.8 270)
			(layer "F.Fab")
			(effects
				(font
					(size 0.7 0.7)
					(thickness 0.15)
				)
				(justify left bottom)
			)
		)
		(fp_text user "Author: Antmicro"
			(at -1.93 5 270)
			(layer "F.Fab")
			(effects
				(font
					(size 0.7 0.7)
					(thickness 0.15)
				)
				(justify left bottom)
			)
		)
		(pad "1" smd rect
			(at -1.301 -0.947 180)
			(size 0.7 1.2)
			(layers "F.Cu" "F.Mask" "F.Paste")
			(net 19 "/CSI/CSI_3V3")
			(pinfunction "OUT")
			(pintype "power_out")
		)
		(pad "2" smd rect
			(at -1.301 0.004 180)
			(size 0.7 1.2)
			(layers "F.Cu" "F.Mask" "F.Paste")
			(net 3 "GND")
			(pinfunction "GND")
			(pintype "power_in")
		)
		(pad "3" smd rect
			(at -1.301 0.954 180)
			(size 0.7 1.2)
			(layers "F.Cu" "F.Mask" "F.Paste")
			(net 371 "Net-(U602-FLG)")
			(pinfunction "FLG")
			(pintype "output")
		)
		(pad "4" smd rect
			(at 1.299 0.954 180)
			(size 0.7 1.2)
			(layers "F.Cu" "F.Mask" "F.Paste")
			(net 369 "/CSI/CamCtrl.EN")
			(pinfunction "EN")
			(pintype "input")
		)
		(pad "5" smd rect
			(at 1.299 0.004 180)
			(size 0.7 1.2)
			(layers "F.Cu" "F.Mask" "F.Paste")
			(net 373 "Net-(U602-ISET)")
			(pinfunction "ISET")
			(pintype "passive")
		)
		(pad "6" smd rect
			(at 1.299 -0.947 180)
			(size 0.7 1.2)
			(layers "F.Cu" "F.Mask" "F.Paste")
			(net 9 "+3V3")
			(pinfunction "IN")
			(pintype "power_in")
		)
	)
)
